(kicad_pcb
	(version 20260206)
	(generator "pcbnew")
	(generator_version "10.0")
	(general
		(thickness 1.6)
		(legacy_teardrops no)
	)
	(paper "A4")
	(title_block
		(title "v1-chassis-manager — T6M_CM_d_v01_1031_1645.brd")
		(comment 1 "Open CloudServer (Microsoft) / footprints 2103-2112 of 2512")
	)
	(layers
		(0 "F.Cu" signal "TOP")
		(4 "In1.Cu" signal "GND1")
		(6 "In2.Cu" signal "IN1")
		(8 "In3.Cu" signal "VCC1")
		(10 "In4.Cu" signal "VCC2")
		(12 "In5.Cu" signal "GND2")
		(14 "In6.Cu" signal "IN2")
		(16 "In7.Cu" signal "IN3")
		(18 "In8.Cu" signal "GND3")
		(2 "B.Cu" signal "BOTTOM")
		(9 "F.Adhes" user "F.Adhesive")
		(11 "B.Adhes" user "B.Adhesive")
		(13 "F.Paste" user "Package Geometry/Pastemask Top")
		(15 "B.Paste" user "Package Geometry/Pastemask Bottom")
		(5 "F.SilkS" user "Ref Des/Silkscreen Top")
		(7 "B.SilkS" user "Ref Des/Silkscreen Bottom")
		(1 "F.Mask" user "Board Geometry/Soldermask Top")
		(3 "B.Mask" user "Board Geometry/Soldermask Bottom")
		(17 "Dwgs.User" user "User.Drawings")
		(19 "Cmts.User" user "User.Comments")
		(21 "Eco1.User" user "User.Eco1")
		(23 "Eco2.User" user "User.Eco2")
		(25 "Edge.Cuts" user "Board Geometry/Outline")
		(27 "Margin" user)
		(31 "F.CrtYd" user "Package Geometry/Place Bound Top")
		(29 "B.CrtYd" user "Package Geometry/Place Bound Bottom")
		(35 "F.Fab" user "Ref Des/Assembly Top")
		(33 "B.Fab" user "Ref Des/Assembly Bottom")
	)
	(footprint ""
		(layer "B.Cu")
		(at 78.83144 -174.537624 180)
		(property "Reference" "R693"
			(at -30.562296 -20.108164 0)
			(unlocked yes)
			(layer "B.SilkS")
			(effects
				(font
					(size 0.7874 0.5842)
					(thickness 0.1524)
				)
				(justify left mirror)
			)
		)
		(property "Value" ""
			(at 0 0 0)
			(layer "B.Fab")
			(effects
				(font
					(size 1.27 1.27)
				)
				(justify mirror)
			)
		)
		(duplicate_pad_numbers_are_jumpers no)
		(fp_line
			(start 0.7874 0.4064)
			(end 0.7874 -0.4064)
			(stroke
				(width 0.1524)
				(type default)
			)
			(layer "B.SilkS")
		)
		(fp_line
			(start 0.7874 -0.4064)
			(end -0.7874 -0.4064)
			(stroke
				(width 0.1524)
				(type default)
			)
			(layer "B.SilkS")
		)
		(fp_line
			(start -0.7874 0.4064)
			(end 0.7874 0.4064)
			(stroke
				(width 0.1524)
				(type default)
			)
			(layer "B.SilkS")
		)
		(fp_line
			(start -0.7874 -0.4064)
			(end -0.7874 0.4064)
			(stroke
				(width 0.1524)
				(type default)
			)
			(layer "B.SilkS")
		)
		(fp_poly
			(pts
				(xy 0.508 0.2794) (xy 0.508 0.2286) (xy 0.635 0.2286) (xy 0.635 -0.254) (xy 0.5334 -0.254) (xy 0.5334 -0.2794)
				(xy -0.5334 -0.2794) (xy -0.5334 -0.254) (xy -0.635 -0.254) (xy -0.635 0.254) (xy -0.5334 0.254)
				(xy -0.5334 0.2794)
			)
			(stroke
				(width 0)
				(type default)
			)
			(fill no)
			(layer "B.CrtYd")
		)
		(pad "1" smd rect
			(at -0.40005 0)
			(size 0.4572 0.508)
			(layers "B.Cu" "B.Mask" "B.Paste")
			(net "T2_NODE1_EN")
		)
		(pad "2" smd rect
			(at 0.40005 0)
			(size 0.4572 0.508)
			(layers "B.Cu" "B.Mask" "B.Paste")
			(net "P5V_NODE1")
		)
	)
	(footprint ""
		(layer "B.Cu")
		(at 103.506524 -165.566852 90)
		(property "Reference" "C576"
			(at -2.20091 2.379726 270)
			(unlocked yes)
			(layer "B.SilkS")
			(effects
				(font
					(size 0.7874 0.5842)
					(thickness 0.1524)
				)
				(justify left mirror)
			)
		)
		(property "Value" ""
			(at 0 0 90)
			(layer "B.Fab")
			(effects
				(font
					(size 1.27 1.27)
				)
				(justify mirror)
			)
		)
		(duplicate_pad_numbers_are_jumpers no)
		(fp_line
			(start 0.7874 -0.4064)
			(end -0.7874 -0.4064)
			(stroke
				(width 0.1524)
				(type default)
			)
			(layer "B.SilkS")
		)
		(fp_line
			(start -0.7874 -0.4064)
			(end -0.7874 0.4064)
			(stroke
				(width 0.1524)
				(type default)
			)
			(layer "B.SilkS")
		)
		(fp_line
			(start 0 0.381)
			(end 0 -0.381)
			(stroke
				(width 0.1524)
				(type default)
			)
			(layer "B.SilkS")
		)
		(fp_line
			(start 0.7874 0.4064)
			(end 0.7874 -0.4064)
			(stroke
				(width 0.1524)
				(type default)
			)
			(layer "B.SilkS")
		)
		(fp_line
			(start -0.7874 0.4064)
			(end 0.7874 0.4064)
			(stroke
				(width 0.1524)
				(type default)
			)
			(layer "B.SilkS")
		)
		(fp_poly
			(pts
				(xy 0.5334 0.254) (xy 0.635 0.254) (xy 0.635 0.2286) (xy 0.635 -0.254) (xy 0.5334 -0.254) (xy 0.5334 -0.2794)
				(xy -0.5334 -0.2794) (xy -0.5334 -0.254) (xy -0.635 -0.254) (xy -0.635 0.254) (xy -0.5334 0.254)
				(xy -0.5334 0.2794) (xy 0.508 0.2794) (xy 0.5334 0.2794)
			)
			(stroke
				(width 0)
				(type default)
			)
			(fill no)
			(layer "B.CrtYd")
		)
		(pad "1" smd rect
			(at -0.40005 0 270)
			(size 0.4572 0.508)
			(layers "B.Cu" "B.Mask" "B.Paste")
			(net "P3V3_NODE1")
		)
		(pad "2" smd rect
			(at 0.40005 0 270)
			(size 0.4572 0.508)
			(layers "B.Cu" "B.Mask" "B.Paste")
			(net "GND")
		)
	)
	(footprint ""
		(layer "B.Cu")
		(at 61.884306 -62.541912)
		(property "Reference" "R34"
			(at -0.385064 2.108962 0)
			(unlocked yes)
			(layer "B.SilkS")
			(effects
				(font
					(size 0.7874 0.5842)
					(thickness 0.1524)
				)
				(justify left mirror)
			)
		)
		(property "Value" ""
			(at 0 0 0)
			(layer "B.Fab")
			(effects
				(font
					(size 1.27 1.27)
				)
				(justify mirror)
			)
		)
		(duplicate_pad_numbers_are_jumpers no)
		(fp_line
			(start -0.7874 -0.4064)
			(end -0.7874 0.4064)
			(stroke
				(width 0.1524)
				(type default)
			)
			(layer "B.SilkS")
		)
		(fp_line
			(start -0.7874 0.4064)
			(end 0.7874 0.4064)
			(stroke
				(width 0.1524)
				(type default)
			)
			(layer "B.SilkS")
		)
		(fp_line
			(start 0.7874 -0.4064)
			(end -0.7874 -0.4064)
			(stroke
				(width 0.1524)
				(type default)
			)
			(layer "B.SilkS")
		)
		(fp_line
			(start 0.7874 0.4064)
			(end 0.7874 -0.4064)
			(stroke
				(width 0.1524)
				(type default)
			)
			(layer "B.SilkS")
		)
		(fp_poly
			(pts
				(xy 0.508 0.2794) (xy 0.508 0.2286) (xy 0.635 0.2286) (xy 0.635 -0.254) (xy 0.5334 -0.254) (xy 0.5334 -0.2794)
				(xy -0.5334 -0.2794) (xy -0.5334 -0.254) (xy -0.635 -0.254) (xy -0.635 0.254) (xy -0.5334 0.254)
				(xy -0.5334 0.2794)
			)
			(stroke
				(width 0)
				(type default)
			)
			(fill no)
			(layer "B.CrtYd")
		)
		(pad "1" smd rect
			(at -0.40005 0 180)
			(size 0.4572 0.508)
			(layers "B.Cu" "B.Mask" "B.Paste")
			(net "M_DDR3_NODE1_MON2P")
		)
		(pad "2" smd rect
			(at 0.40005 0 180)
			(size 0.4572 0.508)
			(layers "B.Cu" "B.Mask" "B.Paste")
			(net "M_DDR3_NODE1_MON2N")
		)
	)
	(footprint ""
		(layer "B.Cu")
		(at 76.408534 -20.939506 90)
		(property "Reference" "C175"
			(at -4.176014 -0.339852 270)
			(unlocked yes)
			(layer "B.SilkS")
			(effects
				(font
					(size 0.7874 0.5842)
					(thickness 0.1524)
				)
				(justify mirror)
			)
		)
		(property "Value" ""
			(at 0 0 90)
			(layer "B.Fab")
			(effects
				(font
					(size 1.27 1.27)
				)
				(justify mirror)
			)
		)
		(duplicate_pad_numbers_are_jumpers no)
		(fp_line
			(start 1.2954 -0.5842)
			(end -1.2954 -0.5842)
			(stroke
				(width 0.1524)
				(type default)
			)
			(layer "B.SilkS")
		)
		(fp_line
			(start 0 -0.5842)
			(end 0 0.5842)
			(stroke
				(width 0.1524)
				(type default)
			)
			(layer "B.SilkS")
		)
		(fp_line
			(start -1.2954 -0.5842)
			(end -1.2954 0.5842)
			(stroke
				(width 0.1524)
				(type default)
			)
			(layer "B.SilkS")
		)
		(fp_line
			(start 1.2954 0.5842)
			(end 1.2954 -0.5842)
			(stroke
				(width 0.1524)
				(type default)
			)
			(layer "B.SilkS")
		)
		(fp_line
			(start -1.2954 0.5842)
			(end 1.2954 0.5842)
			(stroke
				(width 0.1524)
				(type default)
			)
			(layer "B.SilkS")
		)
		(fp_poly
			(pts
				(xy -0.8636 -0.4572) (xy -0.8636 -0.3556) (xy -1.143 -0.3556) (xy -1.143 0.3556) (xy -0.8636 0.3556)
				(xy -0.8636 0.4572) (xy 0.8636 0.4572) (xy 0.8636 0.3556) (xy 1.143 0.3556) (xy 1.143 -0.3556) (xy 0.8636 -0.3556)
				(xy 0.8636 -0.4572)
			)
			(stroke
				(width 0)
				(type default)
			)
			(fill no)
			(layer "B.CrtYd")
		)
		(fp_line
			(start 0.884936 -0.504952)
			(end -0.884936 -0.504952)
			(stroke
				(width 0.1)
				(type default)
			)
			(layer "B.Fab")
		)
		(fp_line
			(start -0.884936 -0.504952)
			(end -0.884936 0.504952)
			(stroke
				(width 0.1)
				(type default)
			)
			(layer "B.Fab")
		)
		(fp_line
			(start 0.884936 0.504952)
			(end 0.884936 -0.504952)
			(stroke
				(width 0.1)
				(type default)
			)
			(layer "B.Fab")
		)
		(fp_line
			(start -0.884936 0.504952)
			(end 0.884936 0.504952)
			(stroke
				(width 0.1)
				(type default)
			)
			(layer "B.Fab")
		)
		(pad "1" smd rect
			(at -0.7366 0 180)
			(size 0.7112 0.8128)
			(layers "B.Cu" "B.Mask" "B.Paste")
			(net "PV_VDDR_NODE1")
		)
		(pad "2" smd rect
			(at 0.7366 0 180)
			(size 0.7112 0.8128)
			(layers "B.Cu" "B.Mask" "B.Paste")
			(net "GND")
		)
	)
	(footprint ""
		(layer "B.Cu")
		(at 126.069852 -141.56055 -90)
		(property "Reference" "C878"
			(at 1.561084 -0.400558 0)
			(unlocked yes)
			(layer "B.SilkS")
			(effects
				(font
					(size 0.7874 0.5842)
					(thickness 0.1524)
				)
				(justify left mirror)
			)
		)
		(property "Value" ""
			(at 0 0 90)
			(layer "B.Fab")
			(effects
				(font
					(size 1.27 1.27)
				)
				(justify mirror)
			)
		)
		(duplicate_pad_numbers_are_jumpers no)
		(fp_line
			(start -0.7874 0.4064)
			(end 0.7874 0.4064)
			(stroke
				(width 0.1524)
				(type default)
			)
			(layer "B.SilkS")
		)
		(fp_line
			(start 0.7874 0.4064)
			(end 0.7874 -0.4064)
			(stroke
				(width 0.1524)
				(type default)
			)
			(layer "B.SilkS")
		)
		(fp_line
			(start 0 0.381)
			(end 0 -0.381)
			(stroke
				(width 0.1524)
				(type default)
			)
			(layer "B.SilkS")
		)
		(fp_line
			(start -0.7874 -0.4064)
			(end -0.7874 0.4064)
			(stroke
				(width 0.1524)
				(type default)
			)
			(layer "B.SilkS")
		)
		(fp_line
			(start 0.7874 -0.4064)
			(end -0.7874 -0.4064)
			(stroke
				(width 0.1524)
				(type default)
			)
			(layer "B.SilkS")
		)
		(fp_poly
			(pts
				(xy 0.5334 0.254) (xy 0.635 0.254) (xy 0.635 0.2286) (xy 0.635 -0.254) (xy 0.5334 -0.254) (xy 0.5334 -0.2794)
				(xy -0.5334 -0.2794) (xy -0.5334 -0.254) (xy -0.635 -0.254) (xy -0.635 0.254) (xy -0.5334 0.254)
				(xy -0.5334 0.2794) (xy 0.508 0.2794) (xy 0.5334 0.2794)
			)
			(stroke
				(width 0)
				(type default)
			)
			(fill no)
			(layer "B.CrtYd")
		)
		(pad "1" smd rect
			(at -0.40005 0 90)
			(size 0.4572 0.508)
			(layers "B.Cu" "B.Mask" "B.Paste")
			(net "P1V0_NODE1")
		)
		(pad "2" smd rect
			(at 0.40005 0 90)
			(size 0.4572 0.508)
			(layers "B.Cu" "B.Mask" "B.Paste")
			(net "GND")
		)
	)
	(footprint ""
		(layer "B.Cu")
		(at 142.07236 -174.029624 180)
		(property "Reference" "R731"
			(at 1.287272 0.298196 0)
			(unlocked yes)
			(layer "B.SilkS")
			(effects
				(font
					(size 0.7874 0.5842)
					(thickness 0.1524)
				)
				(justify left mirror)
			)
		)
		(property "Value" ""
			(at 0 0 0)
			(layer "B.Fab")
			(effects
				(font
					(size 1.27 1.27)
				)
				(justify mirror)
			)
		)
		(duplicate_pad_numbers_are_jumpers no)
		(fp_line
			(start 0.7874 0.4064)
			(end 0.7874 -0.4064)
			(stroke
				(width 0.1524)
				(type default)
			)
			(layer "B.SilkS")
		)
		(fp_line
			(start 0.7874 -0.4064)
			(end -0.7874 -0.4064)
			(stroke
				(width 0.1524)
				(type default)
			)
			(layer "B.SilkS")
		)
		(fp_line
			(start -0.7874 0.4064)
			(end 0.7874 0.4064)
			(stroke
				(width 0.1524)
				(type default)
			)
			(layer "B.SilkS")
		)
		(fp_line
			(start -0.7874 -0.4064)
			(end -0.7874 0.4064)
			(stroke
				(width 0.1524)
				(type default)
			)
			(layer "B.SilkS")
		)
		(fp_poly
			(pts
				(xy 0.508 0.2794) (xy 0.508 0.2286) (xy 0.635 0.2286) (xy 0.635 -0.254) (xy 0.5334 -0.254) (xy 0.5334 -0.2794)
				(xy -0.5334 -0.2794) (xy -0.5334 -0.254) (xy -0.635 -0.254) (xy -0.635 0.254) (xy -0.5334 0.254)
				(xy -0.5334 0.2794)
			)
			(stroke
				(width 0)
				(type default)
			)
			(fill no)
			(layer "B.CrtYd")
		)
		(pad "1" smd rect
			(at -0.40005 0)
			(size 0.4572 0.508)
			(layers "B.Cu" "B.Mask" "B.Paste")
			(net "T9_NODE4_EN")
		)
		(pad "2" smd rect
			(at 0.40005 0)
			(size 0.4572 0.508)
			(layers "B.Cu" "B.Mask" "B.Paste")
			(net "P5V_NODE1")
		)
	)
	(footprint ""
		(layer "B.Cu")
		(at 63.922656 -142.710662)
		(property "Reference" "C258"
			(at -2.386584 0.182118 0)
			(unlocked yes)
			(layer "B.SilkS")
			(effects
				(font
					(size 0.7874 0.5842)
					(thickness 0.1524)
				)
				(justify left mirror)
			)
		)
		(property "Value" ""
			(at 0 0 0)
			(layer "B.Fab")
			(effects
				(font
					(size 1.27 1.27)
				)
				(justify mirror)
			)
		)
		(duplicate_pad_numbers_are_jumpers no)
		(fp_line
			(start -0.7874 -0.4064)
			(end -0.7874 0.4064)
			(stroke
				(width 0.1524)
				(type default)
			)
			(layer "B.SilkS")
		)
		(fp_line
			(start -0.7874 0.4064)
			(end 0.7874 0.4064)
			(stroke
				(width 0.1524)
				(type default)
			)
			(layer "B.SilkS")
		)
		(fp_line
			(start 0 0.381)
			(end 0 -0.381)
			(stroke
				(width 0.1524)
				(type default)
			)
			(layer "B.SilkS")
		)
		(fp_line
			(start 0.7874 -0.4064)
			(end -0.7874 -0.4064)
			(stroke
				(width 0.1524)
				(type default)
			)
			(layer "B.SilkS")
		)
		(fp_line
			(start 0.7874 0.4064)
			(end 0.7874 -0.4064)
			(stroke
				(width 0.1524)
				(type default)
			)
			(layer "B.SilkS")
		)
		(fp_poly
			(pts
				(xy 0.5334 0.254) (xy 0.635 0.254) (xy 0.635 0.2286) (xy 0.635 -0.254) (xy 0.5334 -0.254) (xy 0.5334 -0.2794)
				(xy -0.5334 -0.2794) (xy -0.5334 -0.254) (xy -0.635 -0.254) (xy -0.635 0.254) (xy -0.5334 0.254)
				(xy -0.5334 0.2794) (xy 0.508 0.2794) (xy 0.5334 0.2794)
			)
			(stroke
				(width 0)
				(type default)
			)
			(fill no)
			(layer "B.CrtYd")
		)
		(pad "1" smd rect
			(at -0.40005 0 180)
			(size 0.4572 0.508)
			(layers "B.Cu" "B.Mask" "B.Paste")
			(net "BMC_NODE1_ADCAV33")
		)
		(pad "2" smd rect
			(at 0.40005 0 180)
			(size 0.4572 0.508)
			(layers "B.Cu" "B.Mask" "B.Paste")
			(net "GND")
		)
	)
	(footprint ""
		(layer "B.Cu")
		(at 105.191814 -106.89082)
		(property "Reference" "PC114"
			(at -3.119374 0.200406 0)
			(unlocked yes)
			(layer "B.SilkS")
			(effects
				(font
					(size 0.7874 0.5842)
					(thickness 0.1524)
				)
				(justify left mirror)
			)
		)
		(property "Value" ""
			(at 0 0 0)
			(layer "B.Fab")
			(effects
				(font
					(size 1.27 1.27)
				)
				(justify mirror)
			)
		)
		(duplicate_pad_numbers_are_jumpers no)
		(fp_line
			(start -1.905 -0.8636)
			(end -1.905 0.8636)
			(stroke
				(width 0.1524)
				(type default)
			)
			(layer "B.SilkS")
		)
		(fp_line
			(start -1.905 0.8636)
			(end 1.905 0.8636)
			(stroke
				(width 0.1524)
				(type default)
			)
			(layer "B.SilkS")
		)
		(fp_line
			(start 0 0.8382)
			(end 0 -0.8382)
			(stroke
				(width 0.1524)
				(type default)
			)
			(layer "B.SilkS")
		)
		(fp_line
			(start 1.905 -0.8636)
			(end -1.905 -0.8636)
			(stroke
				(width 0.1524)
				(type default)
			)
			(layer "B.SilkS")
		)
		(fp_line
			(start 1.905 0.8636)
			(end 1.905 -0.8636)
			(stroke
				(width 0.1524)
				(type default)
			)
			(layer "B.SilkS")
		)
		(fp_rect
			(start 1.524 0.7366)
			(end -1.524 -0.7366)
			(stroke
				(width 0)
				(type default)
			)
			(fill no)
			(layer "B.CrtYd")
		)
		(pad "1" smd rect
			(at -0.94996 0 180)
			(size 1.1176 1.3716)
			(layers "B.Cu" "B.Mask" "B.Paste")
			(net "GND")
		)
		(pad "2" smd rect
			(at 0.94996 0 180)
			(size 1.1176 1.3716)
			(layers "B.Cu" "B.Mask" "B.Paste")
			(net "PV_VCCP_NODE1")
		)
	)
	(footprint ""
		(layer "B.Cu")
		(at 151.546814 -67.232022 90)
		(property "Reference" "C362"
			(at 0.02159 5.157724 270)
			(unlocked yes)
			(layer "B.SilkS")
			(effects
				(font
					(size 0.7874 0.5842)
					(thickness 0.1524)
				)
				(justify left mirror)
			)
		)
		(property "Value" ""
			(at 0 0 90)
			(layer "B.Fab")
			(effects
				(font
					(size 1.27 1.27)
				)
				(justify mirror)
			)
		)
		(duplicate_pad_numbers_are_jumpers no)
		(fp_line
			(start 0.7874 -0.4064)
			(end -0.7874 -0.4064)
			(stroke
				(width 0.1524)
				(type default)
			)
			(layer "B.SilkS")
		)
		(fp_line
			(start -0.7874 -0.4064)
			(end -0.7874 0.4064)
			(stroke
				(width 0.1524)
				(type default)
			)
			(layer "B.SilkS")
		)
		(fp_line
			(start 0 0.381)
			(end 0 -0.381)
			(stroke
				(width 0.1524)
				(type default)
			)
			(layer "B.SilkS")
		)
		(fp_line
			(start 0.7874 0.4064)
			(end 0.7874 -0.4064)
			(stroke
				(width 0.1524)
				(type default)
			)
			(layer "B.SilkS")
		)
		(fp_line
			(start -0.7874 0.4064)
			(end 0.7874 0.4064)
			(stroke
				(width 0.1524)
				(type default)
			)
			(layer "B.SilkS")
		)
		(fp_poly
			(pts
				(xy 0.5334 0.254) (xy 0.635 0.254) (xy 0.635 0.2286) (xy 0.635 -0.254) (xy 0.5334 -0.254) (xy 0.5334 -0.2794)
				(xy -0.5334 -0.2794) (xy -0.5334 -0.254) (xy -0.635 -0.254) (xy -0.635 0.254) (xy -0.5334 0.254)
				(xy -0.5334 0.2794) (xy 0.508 0.2794) (xy 0.5334 0.2794)
			)
			(stroke
				(width 0)
				(type default)
			)
			(fill no)
			(layer "B.CrtYd")
		)
		(pad "1" smd rect
			(at -0.40005 0 270)
			(size 0.4572 0.508)
			(layers "B.Cu" "B.Mask" "B.Paste")
			(net "P1V8_SATA_VAA1_NODE1")
		)
		(pad "2" smd rect
			(at 0.40005 0 270)
			(size 0.4572 0.508)
			(layers "B.Cu" "B.Mask" "B.Paste")
			(net "GND")
		)
	)
	(footprint ""
		(layer "B.Cu")
		(at 100.712524 -166.201852 -90)
		(property "Reference" "U71"
			(at 3.591814 -0.305054 0)
			(unlocked yes)
			(layer "B.SilkS")
			(effects
				(font
					(size 0.7874 0.5842)
					(thickness 0.1524)
				)
				(justify mirror)
			)
		)
		(property "Value" ""
			(at 0 0 90)
			(layer "B.Fab")
			(effects
				(font
					(size 1.27 1.27)
				)
				(justify mirror)
			)
		)
		(duplicate_pad_numbers_are_jumpers no)
		(fp_line
			(start -1.651 2.0574)
			(end 1.651 2.0574)
			(stroke
				(width 0.1524)
				(type default)
			)
			(layer "B.SilkS")
		)
		(fp_line
			(start 1.651 2.0574)
			(end 1.651 0.381)
			(stroke
				(width 0.1524)
				(type default)
			)
			(layer "B.SilkS")
		)
		(fp_line
			(start 1.651 0.381)
			(end 1.016 0)
			(stroke
				(width 0.1524)
				(type default)
			)
			(layer "B.SilkS")
		)
		(fp_line
			(start 1.016 0)
			(end 1.651 -0.381)
			(stroke
				(width 0.1524)
				(type default)
			)
			(layer "B.SilkS")
		)
		(fp_line
			(start 1.651 -0.381)
			(end 1.651 -2.0574)
			(stroke
				(width 0.1524)
				(type default)
			)
			(layer "B.SilkS")
		)
		(fp_line
			(start -1.651 -2.0574)
			(end -1.651 2.0574)
			(stroke
				(width 0.1524)
				(type default)
			)
			(layer "B.SilkS")
		)
		(fp_line
			(start 1.651 -2.0574)
			(end -1.651 -2.0574)
			(stroke
				(width 0.1524)
				(type default)
			)
			(layer "B.SilkS")
		)
		(fp_rect
			(start 1.524 1.905)
			(end -1.524 -1.905)
			(stroke
				(width 0)
				(type default)
			)
			(fill no)
			(layer "B.CrtYd")
		)
		(pad "1" smd rect
			(at 0.94996 1.225042 90)
			(size 0.5588 1.3462)
			(layers "B.Cu" "B.Mask" "B.Paste")
			(net "FNACTRL2_TMP_IN")
		)
		(pad "2" smd rect
			(at 0 1.225042 90)
			(size 0.5588 1.3462)
			(layers "B.Cu" "B.Mask" "B.Paste")
			(net "FNACTRL2_T_ST")
		)
		(pad "3" smd rect
			(at -0.94996 1.225042 90)
			(size 0.5588 1.3462)
			(layers "B.Cu" "B.Mask" "B.Paste")
			(net "TMP05_FUNC2")
		)
		(pad "4" smd rect
			(at -0.94996 -1.225042 90)
			(size 0.5588 1.3462)
			(layers "B.Cu" "B.Mask" "B.Paste")
			(net "GND")
		)
		(pad "5" smd rect
			(at 0.94996 -1.225042 90)
			(size 0.5588 1.3462)
			(layers "B.Cu" "B.Mask" "B.Paste")
			(net "P3V3_NODE1")
		)
	)
)
